# TIMECARD (Time Appliance Project (Time Card)) — schematic netlist excerpt (pin names and nets, part order shuffled) for the footprints in the layout excerpt that follows; sources: Cadence DE-HDL packaged netlist, KiCad conversion of R4006-B0001-02_R01.brd

TP17  TP_PIONT  pkg TP010CT020B030_PTH  page 25 : \1\ = R_BNO080_INT_N
L13  FERRITEBEAD  26OHM 25%  pkg SMC_0603R_H030  page 31 : \1\ = XP3R3V ; \2\ = UNNAMED_515_CAPACITOR_I130_1
C155  CAPACITOR  47UF 4V 20%  pkg SMC_0805R_H057  page 14 : \1\ = XP1R0V_FPGA ; \2\ = SG

(kicad_pcb
	(version 20260206)
	(generator "pcbnew")
	(generator_version "10.0")
	(general
		(thickness 1.6)
		(legacy_teardrops no)
	)
	(paper "A4")
	(title_block
		(title "timecard-production-celestica-r4006 — R4006-B0001-02_R01.brd")
		(comment 1 "Time Appliance Project (Time Card) / footprints 304-306 of 1113")
	)
	(layers
		(0 "F.Cu" signal "TOP")
		(4 "In1.Cu" signal "L02_GND1")
		(6 "In2.Cu" signal "L03_SIG1")
		(8 "In3.Cu" signal "L04_GND2")
		(10 "In4.Cu" signal "L05_VCC1")
		(12 "In5.Cu" signal "L06_VCC2")
		(14 "In6.Cu" signal "L07_GND3")
		(16 "In7.Cu" signal "L08_SIG2")
		(18 "In8.Cu" signal "L09_GND4")
		(2 "B.Cu" signal "BOTTOM")
		(9 "F.Adhes" user "F.Adhesive")
		(11 "B.Adhes" user "B.Adhesive")
		(13 "F.Paste" user "Package Geometry/Pastemask Top")
		(15 "B.Paste" user "Package Geometry/Pastemask Bottom")
		(5 "F.SilkS" user "Ref Des/Silkscreen Top")
		(7 "B.SilkS" user "Ref Des/Silkscreen Bottom")
		(1 "F.Mask" user "Board Geometry/Soldermask Top")
		(3 "B.Mask" user "Board Geometry/Soldermask Bottom")
		(17 "Dwgs.User" user "User.Drawings")
		(19 "Cmts.User" user "User.Comments")
		(21 "Eco1.User" user "User.Eco1")
		(23 "Eco2.User" user "User.Eco2")
		(25 "Edge.Cuts" user "Board Geometry/Outline")
		(27 "Margin" user)
		(31 "F.CrtYd" user "Package Geometry/Place Bound Top")
		(29 "B.CrtYd" user "Package Geometry/Place Bound Bottom")
		(35 "F.Fab" user "Ref Des/Assembly Top")
		(33 "B.Fab" user "Ref Des/Assembly Bottom")
	)
	(footprint ""
		(layer "F.Cu")
		(at 144.78 -24.384 -90)
		(property "Reference" "L13"
			(at -1.8415 0.08763 90)
			(unlocked yes)
			(layer "F.SilkS")
			(effects
				(font
					(size 0.7874 0.5842)
					(thickness 0.1524)
				)
				(justify left)
			)
		)
		(property "Value" "VAL*"
			(at -0.9398 3.70967 270)
			(unlocked yes)
			(layer "F.Fab")
			(hide yes)
			(effects
				(font
					(size 0.7874 0.5842)
					(thickness 0.1524)
				)
				(justify left)
			)
		)
		(property "Tolerance" "TOL*"
			(at -0.9906 5.00507 270)
			(unlocked yes)
			(layer "Cmts.User")
			(hide yes)
			(effects
				(font
					(size 0.7874 0.5842)
					(thickness 0.1524)
				)
				(justify left)
			)
		)
		(property "User Part Number" "PARTNUM*"
			(at -2.54 2.46507 270)
			(unlocked yes)
			(layer "Cmts.User")
			(hide yes)
			(effects
				(font
					(size 0.7874 0.5842)
					(thickness 0.1524)
				)
				(justify left)
			)
		)
		(property "Device Type" "FERRITEBEAD-G191-10101-01,26OHA"
			(at -0.9906 1.22047 270)
			(unlocked yes)
			(layer "F.Fab")
			(hide yes)
			(effects
				(font
					(size 0.7874 0.5842)
					(thickness 0.1524)
				)
				(justify left)
			)
		)
		(duplicate_pad_numbers_are_jumpers no)
		(fp_line
			(start -1.3208 0.7112)
			(end -1.3208 -0.7112)
			(stroke
				(width 0.1)
				(type default)
			)
			(layer "F.SilkS")
		)
		(fp_line
			(start 1.3208 0.7112)
			(end -1.3208 0.7112)
			(stroke
				(width 0.1)
				(type default)
			)
			(layer "F.SilkS")
		)
		(fp_line
			(start -1.3208 -0.7112)
			(end 1.3208 -0.7112)
			(stroke
				(width 0.1)
				(type default)
			)
			(layer "F.SilkS")
		)
		(fp_line
			(start 1.3208 -0.7112)
			(end 1.3208 0.7112)
			(stroke
				(width 0.1)
				(type default)
			)
			(layer "F.SilkS")
		)
		(fp_rect
			(start -1.3208 -0.7112)
			(end 1.3208 0.7112)
			(stroke
				(width 0)
				(type default)
			)
			(fill no)
			(layer "F.CrtYd")
		)
		(fp_line
			(start -0.8128 0.4572)
			(end -0.8128 -0.4572)
			(stroke
				(width 0.1)
				(type default)
			)
			(layer "F.Fab")
		)
		(fp_line
			(start 0.8128 0.4572)
			(end -0.8128 0.4572)
			(stroke
				(width 0.1)
				(type default)
			)
			(layer "F.Fab")
		)
		(fp_line
			(start -0.8128 -0.4572)
			(end 0.8128 -0.4572)
			(stroke
				(width 0.1)
				(type default)
			)
			(layer "F.Fab")
		)
		(fp_line
			(start 0.8128 -0.4572)
			(end 0.8128 0.4572)
			(stroke
				(width 0.1)
				(type default)
			)
			(layer "F.Fab")
		)
		(pad "1" smd rect
			(at -0.6858 0 270)
			(size 0.762 0.8636)
			(layers "F.Cu" "F.Mask" "F.Paste")
			(net "XP3R3V")
		)
		(pad "2" smd rect
			(at 0.6858 0 270)
			(size 0.762 0.8636)
			(layers "F.Cu" "F.Mask" "F.Paste")
			(net "UNNAMED_515_CAPACITOR_I130_1")
		)
		(zone
			(layer "F.Cu")
			(hatch none 0.5)
			(connect_pads
				(clearance 0)
			)
			(min_thickness 0.25)
			(keepout
				(tracks allowed)
				(vias not_allowed)
				(pads allowed)
				(copperpour not_allowed)
				(footprints allowed)
			)
			(placement
				(enabled no)
				(sheetname "")
			)
			(fill
				(thermal_gap 0.5)
				(thermal_bridge_width 0.5)
				(island_removal_mode 0)
			)
			(polygon
				(pts
					(xy 145.2372 -24.5364) (xy 144.3228 -24.5364) (xy 144.3228 -24.2316) (xy 145.2372 -24.2316)
				)
			)
		)
	)
	(footprint ""
		(layer "F.Cu")
		(at 89.281 -41.021 90)
		(property "Reference" "C155"
			(at -3.429 -0.21463 90)
			(unlocked yes)
			(layer "F.SilkS")
			(effects
				(font
					(size 0.7874 0.5842)
					(thickness 0.1524)
				)
			)
		)
		(property "Value" "VAL*"
			(at 0.0762 3.134106 90)
			(unlocked yes)
			(layer "F.Fab")
			(hide yes)
			(effects
				(font
					(size 0.7874 0.5842)
					(thickness 0.1524)
				)
			)
		)
		(property "Tolerance" "TOL*"
			(at 0.0762 4.048506 90)
			(unlocked yes)
			(layer "Cmts.User")
			(hide yes)
			(effects
				(font
					(size 0.7874 0.5842)
					(thickness 0.1524)
				)
			)
		)
		(property "User Part Number" "PARTNUM*"
			(at 0.1016 5.013706 90)
			(unlocked yes)
			(layer "Cmts.User")
			(hide yes)
			(effects
				(font
					(size 0.7874 0.5842)
					(thickness 0.1524)
				)
			)
		)
		(property "Device Type" "CAPACITOR-G107-0F476-AM,47UF,2A"
			(at 0.0508 2.194306 90)
			(unlocked yes)
			(layer "F.Fab")
			(hide yes)
			(effects
				(font
					(size 0.7874 0.5842)
					(thickness 0.1524)
				)
			)
		)
		(duplicate_pad_numbers_are_jumpers no)
		(fp_line
			(start 1.5748 -0.9398)
			(end -1.5748 -0.9398)
			(stroke
				(width 0.1)
				(type default)
			)
			(layer "F.SilkS")
		)
		(fp_line
			(start -1.5748 -0.9398)
			(end -1.5748 0.9398)
			(stroke
				(width 0.1)
				(type default)
			)
			(layer "F.SilkS")
		)
		(fp_line
			(start 1.5748 0.9398)
			(end 1.5748 -0.9398)
			(stroke
				(width 0.1)
				(type default)
			)
			(layer "F.SilkS")
		)
		(fp_line
			(start -1.5748 0.9398)
			(end 1.5748 0.9398)
			(stroke
				(width 0.1)
				(type default)
			)
			(layer "F.SilkS")
		)
		(fp_rect
			(start -1.5748 -0.9398)
			(end 1.5748 0.9398)
			(stroke
				(width 0)
				(type default)
			)
			(fill no)
			(layer "F.CrtYd")
		)
		(fp_line
			(start 1.016 -0.635)
			(end -1.016 -0.635)
			(stroke
				(width 0.1)
				(type default)
			)
			(layer "F.Fab")
		)
		(fp_line
			(start -1.016 -0.635)
			(end -1.016 0.635)
			(stroke
				(width 0.1)
				(type default)
			)
			(layer "F.Fab")
		)
		(fp_line
			(start 1.016 0.635)
			(end 1.016 -0.635)
			(stroke
				(width 0.1)
				(type default)
			)
			(layer "F.Fab")
		)
		(fp_line
			(start -1.016 0.635)
			(end 1.016 0.635)
			(stroke
				(width 0.1)
				(type default)
			)
			(layer "F.Fab")
		)
		(pad "1" smd rect
			(at -0.8382 0 90)
			(size 0.9652 1.3716)
			(layers "F.Cu" "F.Mask" "F.Paste")
			(net "XP1R0V_FPGA")
		)
		(pad "2" smd rect
			(at 0.8382 0 90)
			(size 0.9652 1.3716)
			(layers "F.Cu" "F.Mask" "F.Paste")
			(net "SG")
		)
		(zone
			(layer "F.Cu")
			(hatch none 0.5)
			(connect_pads
				(clearance 0)
			)
			(min_thickness 0.25)
			(keepout
				(tracks allowed)
				(vias not_allowed)
				(pads allowed)
				(copperpour not_allowed)
				(footprints allowed)
			)
			(placement
				(enabled no)
				(sheetname "")
			)
			(fill
				(thermal_gap 0.5)
				(thermal_bridge_width 0.5)
				(island_removal_mode 0)
			)
			(polygon
				(pts
					(xy 88.646 -40.7924) (xy 89.916 -40.7924) (xy 89.916 -41.2496) (xy 88.646 -41.2496)
				)
			)
		)
	)
	(footprint ""
		(layer "F.Cu")
		(at 83.947 -67.31)
		(property "Reference" "TP17"
			(at -1.8034 -0.85725 0)
			(unlocked yes)
			(layer "F.SilkS")
			(effects
				(font
					(size 0.635 0.4064)
					(thickness 0.1524)
				)
				(justify left)
			)
		)
		(property "Value" ""
			(at 0 0 0)
			(layer "F.Fab")
			(effects
				(font
					(size 1.27 1.27)
				)
			)
		)
		(property "Device Type" "TP_PIONT-TP010CT020B030_PTH-TPA"
			(at -1.341882 0.996696 0)
			(unlocked yes)
			(layer "F.Fab")
			(hide yes)
			(effects
				(font
					(size 0.7874 0.5842)
					(thickness 0.000001)
				)
				(justify left)
			)
		)
		(duplicate_pad_numbers_are_jumpers no)
		(fp_poly
			(pts
				(arc
					(start 0.889 0)
					(mid -0.889 0)
					(end 0.889 0)
				)
			)
			(stroke
				(width 0)
				(type default)
			)
			(fill no)
			(layer "B.CrtYd")
		)
		(fp_poly
			(pts
				(arc
					(start 0.889 0)
					(mid -0.889 0)
					(end 0.889 0)
				)
			)
			(stroke
				(width 0)
				(type default)
			)
			(fill no)
			(layer "F.CrtYd")
		)
		(pad "1" thru_hole circle
			(at 0 0)
			(size 0.508 0.508)
			(drill 0.254)
			(layers "*.Cu" "*.Mask")
			(remove_unused_layers no)
			(net "R_BNO080_INT_N")
			(clearance 0.1016)
			(padstack
				(mode front_inner_back)
				(layer "Inner"
					(shape circle)
					(size 0.508 0.508)
					(clearance 0.1016)
				)
				(layer "B.Cu"
					(shape circle)
					(size 0.762 0.762)
					(clearance -0.0254)
				)
			)
		)
	)
)
